# T6G (Grand Teton) — schematic netlist excerpt (pin names and nets, part order shuffled) for the footprints in the layout excerpt that follows; sources: Cadence DE-HDL packaged netlist, KiCad conversion of 04192023_DAF0TMB3IC0_F0TG_MB_C_brd_V02_OCP.brd

J15  SCONN288_DDR506112002KQ  IO  pkg DDR288S_1-1VXC  page 87
  VIN_BULK0  = P12V_MEM_CPU0
  RFU0  = NC
  VIN_MGMT  = P3V3_AUX
  HSCL  = I3C_SPD_DDRB_CPU0_SCL
  HSDA  = I3C_SPD_DDRB_CPU0_SDA
  VSS0  = GND
  DQ0_A  = M_B_CPU0_SA_DQ<0>
  VSS1  = GND
  DQ1_A  = M_B_CPU0_SA_DQ<1>
  VSS2  = GND
  DQS0_A_T  = M_B_CPU0_SA_DQS_DP<0>
  DQS0_A_C  = M_B_CPU0_SA_DQS_DN<0>
  VSS3  = GND
  DQ4_A  = M_B_CPU0_SA_DQ<4>
  VSS4  = GND
  DQ5_A  = M_B_CPU0_SA_DQ<5>
  VSS5  = GND
  DQ8_A  = M_B_CPU0_SA_DQ<8>
  VSS6  = GND
  DQ9_A  = M_B_CPU0_SA_DQ<9>
  VSS7  = GND
  DQS1_A_T  = M_B_CPU0_SA_DQS_DP<1>
  DQS1_A_C  = M_B_CPU0_SA_DQS_DN<1>
  VSS8  = GND
  DQ12_A  = M_B_CPU0_SA_DQ<12>
  VSS9  = GND
  DQ13_A  = M_B_CPU0_SA_DQ<13>
  VSS10  = GND
  DQ16_A  = M_B_CPU0_SA_DQ<16>
  VSS11  = GND
  DQ17_A  = M_B_CPU0_SA_DQ<17>
  VSS12  = GND
  DQS2_A_T  = M_B_CPU0_SA_DQS_DP<2>
  DQS2_A_C  = M_B_CPU0_SA_DQS_DN<2>
  VSS13  = GND
  DQ20_A  = M_B_CPU0_SA_DQ<20>
  VSS14  = GND
  DQ21_A  = M_B_CPU0_SA_DQ<21>
  VSS15  = GND
  DQ24_A  = M_B_CPU0_SA_DQ<24>
  VSS16  = GND
  DQ25_A  = M_B_CPU0_SA_DQ<25>
  VSS17  = GND
  DQS3_A_T  = M_B_CPU0_SA_DQS_DP<3>
  DQS3_A_C  = M_B_CPU0_SA_DQS_DN<3>
  VSS18  = GND
  DQ28_A  = M_B_CPU0_SA_DQ<28>
  VSS19  = GND
  DQ29_A  = M_B_CPU0_SA_DQ<29>
  VSS20  = GND
  CB0_A  = M_B_CPU0_SA_CB<0>
  VSS21  = GND
  CB1_A  = M_B_CPU0_SA_CB<1>
  VSS22  = GND
  DQS4_A_T  = M_B_CPU0_SA_DQS_DP<4>
  DQS4_A_C  = M_B_CPU0_SA_DQS_DN<4>
  VSS23  = GND
  CB4_A  = M_B_CPU0_SA_CB<4>
  VSS24  = GND
  CB5_A  = M_B_CPU0_SA_CB<5>
  VSS25  = GND
  ALERT_N  = M_B_CPU0_ALERT_N
  VSS26  = GND
  CS0_A_N  = M_B_CPU0_SA_CS_N<0>
  VSS27  = GND
  CA0_A  = M_B_CPU0_SA_CA<0>
  VSS28  = GND
  CA2_A  = M_B_CPU0_SA_CA<2>
  VSS29  = GND
  CA4_A  = M_B_CPU0_SA_CA<4>
  VSS30  = GND
  CA6_A  = M_B_CPU0_SA_CA<6>
  VSS31  = GND
  PAR_A  = M_B_CPU0_SA_PAR
  VSS32  = GND
  CA0_B  = M_B_CPU0_SB_CA<0>
  VSS33  = GND
  CA2_B  = M_B_CPU0_SB_CA<2>
  VSS34  = GND
  CA4_B  = M_B_CPU0_SB_CA<4>
  VSS35  = GND
  CA6_B  = M_B_CPU0_SB_CA<6>
  VSS36  = GND
  CS0_B_N  = M_B_CPU0_SB_CS_N<0>
  VSS37  = GND
  \lbd||rsp_a_n\  = M_B_CPU0_SA_RSP<0>
  \lbs||rsp_b_n\  = M_B_CPU0_SB_RSP<0>
  VSS38  = GND
  CB4_B  = M_B_CPU0_SB_CB<4>
  VSS39  = GND
  CB5_B  = M_B_CPU0_SB_CB<5>
  VSS40  = GND
  \dqs9_b_t||tdqs9_b_t||dbi4_b_n\  = M_B_CPU0_SB_DQS_DP<9>
  \dqs9_b_c||tdqs9_b_c\  = M_B_CPU0_SB_DQS_DN<9>
  VSS41  = GND
  CB0_B  = M_B_CPU0_SB_CB<0>
  VSS42  = GND
  CB1_B  = M_B_CPU0_SB_CB<1>
  VSS43  = GND
  DQ0_B  = M_B_CPU0_SB_DQ<0>
  VSS44  = GND
  DQ1_B  = M_B_CPU0_SB_DQ<1>
  VSS45  = GND
  DQS0_B_T  = M_B_CPU0_SB_DQS_DP<0>
  DQS0_B_C  = M_B_CPU0_SB_DQS_DN<0>
  VSS46  = GND
  DQ4_B  = M_B_CPU0_SB_DQ<4>
  VSS47  = GND
  DQ5_B  = M_B_CPU0_SB_DQ<5>
  VSS48  = GND
  DQ8_B  = M_B_CPU0_SB_DQ<8>
  VSS49  = GND
  DQ9_B  = M_B_CPU0_SB_DQ<9>
  VSS50  = GND
  DQS1_B_T  = M_B_CPU0_SB_DQS_DP<1>
  DQS1_B_C  = M_B_CPU0_SB_DQS_DN<1>
  VSS51  = GND
  DQ12_B  = M_B_CPU0_SB_DQ<12>
  VSS52  = GND
  DQ13_B  = M_B_CPU0_SB_DQ<13>
  VSS53  = GND
  DQ16_B  = M_B_CPU0_SB_DQ<16>
  VSS54  = GND
  DQ17_B  = M_B_CPU0_SB_DQ<17>
  VSS55  = GND
  DQS2_B_T  = M_B_CPU0_SB_DQS_DP<2>
  DQS2_B_C  = M_B_CPU0_SB_DQS_DN<2>
  VSS56  = GND
  DQ20_B  = M_B_CPU0_SB_DQ<20>
  VSS57  = GND
  DQ21_B  = M_B_CPU0_SB_DQ<21>
  VSS58  = GND
  DQ24_B  = M_B_CPU0_SB_DQ<24>
  VSS59  = GND
  DQ25_B  = M_B_CPU0_SB_DQ<25>
  VSS60  = GND
  DQS3_B_T  = M_B_CPU0_SB_DQS_DP<3>
  DQS3_B_C  = M_B_CPU0_SB_DQS_DN<3>
  VSS61  = GND
  DQ28_B  = M_B_CPU0_SB_DQ<28>
  VSS62  = GND
  DQ29_B  = M_B_CPU0_SB_DQ<29>
  VSS63  = GND
  RFU1  = NC
  VIN_BULK1  = P12V_MEM_CPU0
  VIN_BULK2  = P12V_MEM_CPU0
  \pwr_good||fail_n\  = PWRGD_CHB_CPU0_DIMM
  HAS  = PD_CHB_CPU0_DIMM_SAA
  RFU2  = NC
  RFU3  = NC
  VSS64  = GND
  DQ2_A  = M_B_CPU0_SA_DQ<2>
  VSS65  = GND
  DQ3_A  = M_B_CPU0_SA_DQ<3>
  VSS66  = GND
  \dqs5_a_c||tdqs5_a_c||dqs5_a_t||tdqs5_a_t\  = M_B_CPU0_SA_DQS_DN<5>
  \dqs5_a_t||tdqs5_a_t\  = M_B_CPU0_SA_DQS_DP<5>
  VSS67  = GND
  DQ6_A  = M_B_CPU0_SA_DQ<6>
  VSS68  = GND
  DQ7_A  = M_B_CPU0_SA_DQ<7>
  VSS69  = GND
  DQ10_A  = M_B_CPU0_SA_DQ<10>
  VSS70  = GND
  DQ11_A  = M_B_CPU0_SA_DQ<11>
  VSS71  = GND
  \dqs6_a_c||tdqs6_a_c||dqs6_a_t||tdqs6_a_t\  = M_B_CPU0_SA_DQS_DN<6>
  \dqs6_a_t||tdqs6_a_t\  = M_B_CPU0_SA_DQS_DP<6>
  VSS72  = GND
  DQ14_A  = M_B_CPU0_SA_DQ<14>
  VSS73  = GND
  DQ15_A  = M_B_CPU0_SA_DQ<15>
  VSS74  = GND
  DQ18_A  = M_B_CPU0_SA_DQ<18>
  VSS75  = GND
  DQ19_A  = M_B_CPU0_SA_DQ<19>
  VSS76  = GND
  \dqs7_a_c||tdqs7_a_c\  = M_B_CPU0_SA_DQS_DN<7>
  \dqs7_a_t||tdqs7_a_t\  = M_B_CPU0_SA_DQS_DP<7>
  VSS77  = GND
  DQ22_A  = M_B_CPU0_SA_DQ<22>
  VSS78  = GND
  DQ23_A  = M_B_CPU0_SA_DQ<23>
  VSS79  = GND
  DQ26_A  = M_B_CPU0_SA_DQ<26>
  VSS80  = GND
  DQ27_A  = M_B_CPU0_SA_DQ<27>
  VSS81  = GND
  \dqs8_a_c||tdqs8_a_c\  = M_B_CPU0_SA_DQS_DN<8>
  \dqs8_a_t||tdqs8_a_t\  = M_B_CPU0_SA_DQS_DP<8>
  VSS82  = GND
  DQ30_A  = M_B_CPU0_SA_DQ<30>
  VSS83  = GND
  DQ31_A  = M_B_CPU0_SA_DQ<31>
  VSS84  = GND
  CB2_A  = M_B_CPU0_SA_CB<2>
  VSS85  = GND
  CB3_A  = M_B_CPU0_SA_CB<3>
  VSS86  = GND
  \dqs9_a_c||tdqs9_a_c\  = M_B_CPU0_SA_DQS_DN<9>
  \dqs9_a_t||tdqs9_a_t\  = M_B_CPU0_SA_DQS_DP<9>
  VSS87  = GND
  CB6_A  = M_B_CPU0_SA_CB<6>
  VSS88  = GND
  CB7_A  = M_B_CPU0_SA_CB<7>
  VSS89  = GND
  RESET_N  = M_B_CPU0_RESET_N
  VSS90  = GND
  CS1_A_N  = M_B_CPU0_SA_CS_N<1>
  VSS91  = GND
  CA1_A  = M_B_CPU0_SA_CA<1>
  VSS92  = GND
  CA3_A  = M_B_CPU0_SA_CA<3>
  VSS93  = GND
  CA5_A  = M_B_CPU0_SA_CA<5>
  VSS94  = GND
  CK_T  = M_B_CPU0_CLK_DP<0>
  CK_C  = M_B_CPU0_CLK_DN<0>
  VSS95  = GND
  RFU4  = NC
  CA1_B  = M_B_CPU0_SB_CA<1>
  VSS96  = GND
  CA3_B  = M_B_CPU0_SB_CA<3>
  VSS97  = GND
  CA5_B  = M_B_CPU0_SB_CA<5>
  VSS98  = GND
  PAR_B  = M_B_CPU0_SB_PAR
  VSS99  = GND
  CS1_B_N  = M_B_CPU0_SB_CS_N<1>
  VSS100  = GND
  RFU5  = NC
  RFU6  = NC
  VSS101  = GND
  CB6_B  = M_B_CPU0_SB_CB<6>
  VSS102  = GND
  CB7_B  = M_B_CPU0_SB_CB<7>
  VSS103  = GND
  DQS4_B_C  = M_B_CPU0_SB_DQS_DN<4>
  DQS4_B_T  = M_B_CPU0_SB_DQS_DP<4>
  VSS104  = GND
  CB2_B  = M_B_CPU0_SB_CB<2>
  VSS105  = GND
  CB3_B  = M_B_CPU0_SB_CB<3>
  VSS106  = GND
  DQ2_B  = M_B_CPU0_SB_DQ<2>
  VSS107  = GND
  DQ3_B  = M_B_CPU0_SB_DQ<3>
  VSS108  = GND
  \dqs5_b_c||tdqs5_b_c\  = M_B_CPU0_SB_DQS_DN<5>
  \dqs5_b_t||tdqs5_b_t\  = M_B_CPU0_SB_DQS_DP<5>
  VSS109  = GND
  DQ6_B  = M_B_CPU0_SB_DQ<6>
  VSS110  = GND
  DQ7_B  = M_B_CPU0_SB_DQ<7>
  VSS111  = GND
  DQ10_B  = M_B_CPU0_SB_DQ<10>
  VSS112  = GND
  DQ11_B  = M_B_CPU0_SB_DQ<11>
  VSS113  = GND
  \dqs6_b_c||tdqs6_b_c\  = M_B_CPU0_SB_DQS_DN<6>
  \dqs6_b_t||tdqs6_b_t\  = M_B_CPU0_SB_DQS_DP<6>
  VSS114  = GND
  DQ14_B  = M_B_CPU0_SB_DQ<14>
  VSS115  = GND
  DQ15_B  = M_B_CPU0_SB_DQ<15>
  VSS116  = GND
  DQ18_B  = M_B_CPU0_SB_DQ<18>
  VSS117  = GND
  DQ19_B  = M_B_CPU0_SB_DQ<19>
  VSS118  = GND
  \dqs7_b_c||tdqs7_b_c\  = M_B_CPU0_SB_DQS_DN<7>
  \dqs7_b_t||tdqs7_b_t\  = M_B_CPU0_SB_DQS_DP<7>
  VSS119  = GND
  DQ22_B  = M_B_CPU0_SB_DQ<22>
  VSS120  = GND
  DQ23_B  = M_B_CPU0_SB_DQ<23>
  VSS121  = GND
  DQ26_B  = M_B_CPU0_SB_DQ<26>
  VSS122  = GND
  DQ27_B  = M_B_CPU0_SB_DQ<27>
  VSS123  = GND
  \dqs8_b_c||tdqs8_b_c\  = M_B_CPU0_SB_DQS_DN<8>
  \dqs8_b_t||tdqs8_b_t\  = M_B_CPU0_SB_DQS_DP<8>
  VSS124  = GND
  DQ30_B  = M_B_CPU0_SB_DQ<30>
  VSS125  = GND
  DQ31_B  = M_B_CPU0_SB_DQ<31>
  VSS126  = GND
  G1  = GND
  G2  = GND
  G3  = GND

(kicad_pcb
	(version 20260206)
	(generator "pcbnew")
	(generator_version "10.0")
	(general
		(thickness 1.6)
		(legacy_teardrops no)
	)
	(paper "A4")
	(title_block
		(title "04192023_DAF0TMB3IC0_F0TG_MB_C_brd_V02_OCP.brd")
		(comment 1 "Grand Teton / footprint 1120 of 8354 (J15), pads 231-276 of 291")
	)
	(layers
		(0 "F.Cu" signal "TOP")
		(4 "In1.Cu" signal "GND")
		(6 "In2.Cu" signal "IN1")
		(8 "In3.Cu" signal "GND1")
		(10 "In4.Cu" signal "IN2")
		(12 "In5.Cu" signal "GND2")
		(14 "In6.Cu" signal "IN3")
		(16 "In7.Cu" signal "GND3")
		(18 "In8.Cu" signal "VCC")
		(20 "In9.Cu" signal "VCC1")
		(22 "In10.Cu" signal "GND4")
		(24 "In11.Cu" signal "IN4")
		(26 "In12.Cu" signal "GND5")
		(28 "In13.Cu" signal "IN5")
		(30 "In14.Cu" signal "GND6")
		(32 "In15.Cu" signal "IN6")
		(34 "In16.Cu" signal "GND7")
		(2 "B.Cu" signal "BOTTOM")
		(9 "F.Adhes" user "F.Adhesive")
		(11 "B.Adhes" user "B.Adhesive")
		(13 "F.Paste" user "Package Geometry/Pastemask Top")
		(15 "B.Paste" user "Package Geometry/Pastemask Bottom")
		(5 "F.SilkS" user "Ref Des/Silkscreen Top")
		(7 "B.SilkS" user "Ref Des/Silkscreen Bottom")
		(1 "F.Mask" user "Board Geometry/Soldermask Top")
		(3 "B.Mask" user "Board Geometry/Soldermask Bottom")
		(17 "Dwgs.User" user "User.Drawings")
		(19 "Cmts.User" user "User.Comments")
		(21 "Eco1.User" user "User.Eco1")
		(23 "Eco2.User" user "User.Eco2")
		(25 "Edge.Cuts" user "Board Geometry/Outline")
		(27 "Margin" user)
		(31 "F.CrtYd" user "Package Geometry/Place Bound Top")
		(29 "B.CrtYd" user "Package Geometry/Place Bound Bottom")
		(35 "F.Fab" user "Ref Des/Assembly Top")
		(33 "B.Fab" user "Ref Des/Assembly Bottom")
	)
	(footprint ""
		(layer "F.Cu")
		(at 297.774106 -255.560068 180)
		(property "Reference" "J15"
			(at -2.2098 -81.984088 0)
			(unlocked yes)
			(layer "F.SilkS")
			(effects
				(font
					(size 0.7874 0.5842)
					(thickness 0.1524)
				)
			)
		)
		(property "Value" ""
			(at 0 0 180)
			(layer "F.Fab")
			(effects
				(font
					(size 1.27 1.27)
				)
			)
		)
		(duplicate_pad_numbers_are_jumpers no)
		(pad "231" smd rect
			(at 2.050034 14.875002 90)
			(size 0.519938 1.4986)
			(layers "F.Cu" "F.Mask" "F.Paste")
			(net "Net_2268")
		)
		(pad "232" smd rect
			(at 2.050034 15.724886 90)
			(size 0.519938 1.4986)
			(layers "F.Cu" "F.Mask" "F.Paste")
			(net "Net_2269")
		)
		(pad "233" smd rect
			(at 2.050034 16.575024 90)
			(size 0.519938 1.4986)
			(layers "F.Cu" "F.Mask" "F.Paste")
			(net "GND")
		)
		(pad "234" smd rect
			(at 2.050034 17.424908 90)
			(size 0.519938 1.4986)
			(layers "F.Cu" "F.Mask" "F.Paste")
			(net "M_B_CPU0_SB_CB<6>")
		)
		(pad "235" smd rect
			(at 2.050034 18.275046 90)
			(size 0.519938 1.4986)
			(layers "F.Cu" "F.Mask" "F.Paste")
			(net "GND")
		)
		(pad "236" smd rect
			(at 2.050034 19.12493 90)
			(size 0.519938 1.4986)
			(layers "F.Cu" "F.Mask" "F.Paste")
			(net "M_B_CPU0_SB_CB<7>")
		)
		(pad "237" smd rect
			(at 2.050034 19.975068 90)
			(size 0.519938 1.4986)
			(layers "F.Cu" "F.Mask" "F.Paste")
			(net "GND")
		)
		(pad "238" smd rect
			(at 2.050034 20.824952 90)
			(size 0.519938 1.4986)
			(layers "F.Cu" "F.Mask" "F.Paste")
			(net "M_B_CPU0_SB_DQS_DN<4>")
		)
		(pad "239" smd rect
			(at 2.050034 21.67509 90)
			(size 0.519938 1.4986)
			(layers "F.Cu" "F.Mask" "F.Paste")
			(net "M_B_CPU0_SB_DQS_DP<4>")
		)
		(pad "240" smd rect
			(at 2.050034 22.524974 90)
			(size 0.519938 1.4986)
			(layers "F.Cu" "F.Mask" "F.Paste")
			(net "GND")
		)
		(pad "241" smd rect
			(at 2.050034 23.375112 90)
			(size 0.519938 1.4986)
			(layers "F.Cu" "F.Mask" "F.Paste")
			(net "M_B_CPU0_SB_CB<2>")
		)
		(pad "242" smd rect
			(at 2.050034 24.224996 90)
			(size 0.519938 1.4986)
			(layers "F.Cu" "F.Mask" "F.Paste")
			(net "GND")
		)
		(pad "243" smd rect
			(at 2.050034 25.07488 90)
			(size 0.519938 1.4986)
			(layers "F.Cu" "F.Mask" "F.Paste")
			(net "M_B_CPU0_SB_CB<3>")
		)
		(pad "244" smd rect
			(at 2.050034 25.925018 90)
			(size 0.519938 1.4986)
			(layers "F.Cu" "F.Mask" "F.Paste")
			(net "GND")
		)
		(pad "245" smd rect
			(at 2.050034 26.774902 90)
			(size 0.519938 1.4986)
			(layers "F.Cu" "F.Mask" "F.Paste")
			(net "M_B_CPU0_SB_DQ<2>")
		)
		(pad "246" smd rect
			(at 2.050034 27.62504 90)
			(size 0.519938 1.4986)
			(layers "F.Cu" "F.Mask" "F.Paste")
			(net "GND")
		)
		(pad "247" smd rect
			(at 2.050034 28.474924 90)
			(size 0.519938 1.4986)
			(layers "F.Cu" "F.Mask" "F.Paste")
			(net "M_B_CPU0_SB_DQ<3>")
		)
		(pad "248" smd rect
			(at 2.050034 29.325062 90)
			(size 0.519938 1.4986)
			(layers "F.Cu" "F.Mask" "F.Paste")
			(net "GND")
		)
		(pad "249" smd rect
			(at 2.050034 30.174946 90)
			(size 0.519938 1.4986)
			(layers "F.Cu" "F.Mask" "F.Paste")
			(net "M_B_CPU0_SB_DQS_DN<5>")
		)
		(pad "250" smd rect
			(at 2.050034 31.025084 90)
			(size 0.519938 1.4986)
			(layers "F.Cu" "F.Mask" "F.Paste")
			(net "M_B_CPU0_SB_DQS_DP<5>")
		)
		(pad "251" smd rect
			(at 2.050034 31.874968 90)
			(size 0.519938 1.4986)
			(layers "F.Cu" "F.Mask" "F.Paste")
			(net "GND")
		)
		(pad "252" smd rect
			(at 2.050034 32.725106 90)
			(size 0.519938 1.4986)
			(layers "F.Cu" "F.Mask" "F.Paste")
			(net "M_B_CPU0_SB_DQ<6>")
		)
		(pad "253" smd rect
			(at 2.050034 33.57499 90)
			(size 0.519938 1.4986)
			(layers "F.Cu" "F.Mask" "F.Paste")
			(net "GND")
		)
		(pad "254" smd rect
			(at 2.050034 34.425128 90)
			(size 0.519938 1.4986)
			(layers "F.Cu" "F.Mask" "F.Paste")
			(net "M_B_CPU0_SB_DQ<7>")
		)
		(pad "255" smd rect
			(at 2.050034 35.275012 90)
			(size 0.519938 1.4986)
			(layers "F.Cu" "F.Mask" "F.Paste")
			(net "GND")
		)
		(pad "256" smd rect
			(at 2.050034 36.124896 90)
			(size 0.519938 1.4986)
			(layers "F.Cu" "F.Mask" "F.Paste")
			(net "M_B_CPU0_SB_DQ<10>")
		)
		(pad "257" smd rect
			(at 2.050034 36.975034 90)
			(size 0.519938 1.4986)
			(layers "F.Cu" "F.Mask" "F.Paste")
			(net "GND")
		)
		(pad "258" smd rect
			(at 2.050034 37.824918 90)
			(size 0.519938 1.4986)
			(layers "F.Cu" "F.Mask" "F.Paste")
			(net "M_B_CPU0_SB_DQ<11>")
		)
		(pad "259" smd rect
			(at 2.050034 38.675056 90)
			(size 0.519938 1.4986)
			(layers "F.Cu" "F.Mask" "F.Paste")
			(net "GND")
		)
		(pad "260" smd rect
			(at 2.050034 39.52494 90)
			(size 0.519938 1.4986)
			(layers "F.Cu" "F.Mask" "F.Paste")
			(net "M_B_CPU0_SB_DQS_DN<6>")
		)
		(pad "261" smd rect
			(at 2.050034 40.375078 90)
			(size 0.519938 1.4986)
			(layers "F.Cu" "F.Mask" "F.Paste")
			(net "M_B_CPU0_SB_DQS_DP<6>")
		)
		(pad "262" smd rect
			(at 2.050034 41.224962 90)
			(size 0.519938 1.4986)
			(layers "F.Cu" "F.Mask" "F.Paste")
			(net "GND")
		)
		(pad "263" smd rect
			(at 2.050034 42.0751 90)
			(size 0.519938 1.4986)
			(layers "F.Cu" "F.Mask" "F.Paste")
			(net "M_B_CPU0_SB_DQ<14>")
		)
		(pad "264" smd rect
			(at 2.050034 42.924984 90)
			(size 0.519938 1.4986)
			(layers "F.Cu" "F.Mask" "F.Paste")
			(net "GND")
		)
		(pad "265" smd rect
			(at 2.050034 43.775122 90)
			(size 0.519938 1.4986)
			(layers "F.Cu" "F.Mask" "F.Paste")
			(net "M_B_CPU0_SB_DQ<15>")
		)
		(pad "266" smd rect
			(at 2.050034 44.625006 90)
			(size 0.519938 1.4986)
			(layers "F.Cu" "F.Mask" "F.Paste")
			(net "GND")
		)
		(pad "267" smd rect
			(at 2.050034 45.47489 90)
			(size 0.519938 1.4986)
			(layers "F.Cu" "F.Mask" "F.Paste")
			(net "M_B_CPU0_SB_DQ<18>")
		)
		(pad "268" smd rect
			(at 2.050034 46.325028 90)
			(size 0.519938 1.4986)
			(layers "F.Cu" "F.Mask" "F.Paste")
			(net "GND")
		)
		(pad "269" smd rect
			(at 2.050034 47.174912 90)
			(size 0.519938 1.4986)
			(layers "F.Cu" "F.Mask" "F.Paste")
			(net "M_B_CPU0_SB_DQ<19>")
		)
		(pad "270" smd rect
			(at 2.050034 48.02505 90)
			(size 0.519938 1.4986)
			(layers "F.Cu" "F.Mask" "F.Paste")
			(net "GND")
		)
		(pad "271" smd rect
			(at 2.050034 48.874934 90)
			(size 0.519938 1.4986)
			(layers "F.Cu" "F.Mask" "F.Paste")
			(net "M_B_CPU0_SB_DQS_DN<7>")
		)
		(pad "272" smd rect
			(at 2.050034 49.725072 90)
			(size 0.519938 1.4986)
			(layers "F.Cu" "F.Mask" "F.Paste")
			(net "M_B_CPU0_SB_DQS_DP<7>")
		)
		(pad "273" smd rect
			(at 2.050034 50.574956 90)
			(size 0.519938 1.4986)
			(layers "F.Cu" "F.Mask" "F.Paste")
			(net "GND")
		)
		(pad "274" smd rect
			(at 2.050034 51.425094 90)
			(size 0.519938 1.4986)
			(layers "F.Cu" "F.Mask" "F.Paste")
			(net "M_B_CPU0_SB_DQ<22>")
		)
		(pad "275" smd rect
			(at 2.050034 52.274978 90)
			(size 0.519938 1.4986)
			(layers "F.Cu" "F.Mask" "F.Paste")
			(net "GND")
		)
		(pad "276" smd rect
			(at 2.050034 53.125116 90)
			(size 0.519938 1.4986)
			(layers "F.Cu" "F.Mask" "F.Paste")
			(net "M_B_CPU0_SB_DQ<23>")
		)
	)
)
